# BASEBOARD_FAB2 (Tioga Pass) — schematic netlist excerpt (pin names and nets, part order shuffled) for the footprints in the layout excerpt that follows; sources: Cadence DE-HDL packaged netlist, KiCad conversion of Wiwynn_Tioga_Pass_MB.brd

C8M2  CAP_A  47UF 4V 20% X5R  pkg 0603V  page 228 : A = PVDDQ_KLM ; B = GND
R784  RES  0.0 5% CHIP  pkg 0402  page 244 : A = P3E_CPU0_PE1_PCH_RXN<8> ; B = P3E_CPU0_PE1_PCH_CON_RXN<8>
R6P28  RES  4.02K 1% CHIP  pkg 0402  page 201 : A = VR_PVCCIN_CPU0_XADDR1 ; B = GND

(kicad_pcb
	(version 20260206)
	(generator "pcbnew")
	(generator_version "10.0")
	(general
		(thickness 1.6)
		(legacy_teardrops no)
	)
	(paper "A4")
	(title_block
		(title "Wiwynn_Tioga_Pass_MB.brd")
		(comment 1 "Tioga Pass / footprints 4055-4057 of 4770")
	)
	(layers
		(0 "F.Cu" signal "TOP")
		(4 "In1.Cu" signal "L2GND")
		(6 "In2.Cu" signal "L3")
		(8 "In3.Cu" signal "L4GND")
		(10 "In4.Cu" signal "L5")
		(12 "In5.Cu" signal "L6GND")
		(14 "In6.Cu" signal "L7VCC")
		(16 "In7.Cu" signal "L8VCC")
		(18 "In8.Cu" signal "L9GND")
		(20 "In9.Cu" signal "L10")
		(22 "In10.Cu" signal "L11GND")
		(24 "In11.Cu" signal "L12")
		(26 "In12.Cu" signal "L13GND")
		(2 "B.Cu" signal "BOTTOM")
		(9 "F.Adhes" user "F.Adhesive")
		(11 "B.Adhes" user "B.Adhesive")
		(13 "F.Paste" user "Package Geometry/Pastemask Top")
		(15 "B.Paste" user "Package Geometry/Pastemask Bottom")
		(5 "F.SilkS" user "Ref Des/Silkscreen Top")
		(7 "B.SilkS" user "Ref Des/Silkscreen Bottom")
		(1 "F.Mask" user "Board Geometry/Soldermask Top")
		(3 "B.Mask" user "Board Geometry/Soldermask Bottom")
		(17 "Dwgs.User" user "User.Drawings")
		(19 "Cmts.User" user "User.Comments")
		(21 "Eco1.User" user "User.Eco1")
		(23 "Eco2.User" user "User.Eco2")
		(25 "Edge.Cuts" user "Board Geometry/Outline")
		(27 "Margin" user)
		(31 "F.CrtYd" user "Package Geometry/Place Bound Top")
		(29 "B.CrtYd" user "Package Geometry/Place Bound Bottom")
		(35 "F.Fab" user "Ref Des/Assembly Top")
		(33 "B.Fab" user "Ref Des/Assembly Bottom")
	)
	(footprint ""
		(layer "B.Cu")
		(at 183.515 -72.8472)
		(property "Reference" "R6P28"
			(at 0 0 0)
			(layer "B.SilkS")
			(hide yes)
			(effects
				(font
					(size 1.27 1.27)
				)
				(justify mirror)
			)
		)
		(property "Value" ""
			(at 0 0 0)
			(layer "B.Fab")
			(effects
				(font
					(size 1.27 1.27)
				)
				(justify mirror)
			)
		)
		(duplicate_pad_numbers_are_jumpers no)
		(fp_rect
			(start -0.2794 0.9906)
			(end 0.2794 -0.1016)
			(stroke
				(width 0)
				(type default)
			)
			(fill no)
			(layer "B.CrtYd")
		)
		(fp_line
			(start -0.2794 -0.1016)
			(end 0.2794 -0.1016)
			(stroke
				(width 0.1)
				(type default)
			)
			(layer "B.Fab")
		)
		(fp_line
			(start -0.2794 0.9906)
			(end -0.2794 -0.1016)
			(stroke
				(width 0.1)
				(type default)
			)
			(layer "B.Fab")
		)
		(fp_line
			(start 0.2794 -0.1016)
			(end 0.2794 0.9906)
			(stroke
				(width 0.1)
				(type default)
			)
			(layer "B.Fab")
		)
		(fp_line
			(start 0.2794 0.9906)
			(end -0.2794 0.9906)
			(stroke
				(width 0.1)
				(type default)
			)
			(layer "B.Fab")
		)
		(pad "1" smd rect
			(at 0 0 180)
			(size 0.508 0.508)
			(layers "B.Cu" "B.Mask" "B.Paste")
			(net "VR_PVCCIN_CPU0_XADDR1")
		)
		(pad "2" smd rect
			(at 0 0.889 180)
			(size 0.508 0.508)
			(layers "B.Cu" "B.Mask" "B.Paste")
			(net "GND")
		)
		(zone
			(layer "B.Cu")
			(hatch none 0.5)
			(connect_pads
				(clearance 0)
			)
			(min_thickness 0.25)
			(keepout
				(tracks not_allowed)
				(vias allowed)
				(pads allowed)
				(copperpour not_allowed)
				(footprints allowed)
			)
			(placement
				(enabled no)
				(sheetname "")
			)
			(fill
				(thermal_gap 0.5)
				(thermal_bridge_width 0.5)
				(island_removal_mode 0)
			)
			(polygon
				(pts
					(xy 183.261 -72.2122) (xy 183.769 -72.2122) (xy 183.769 -72.5932) (xy 183.261 -72.5932)
				)
			)
		)
		(zone
			(layer "B.Cu")
			(hatch none 0.5)
			(connect_pads
				(clearance 0)
			)
			(min_thickness 0.25)
			(keepout
				(tracks allowed)
				(vias not_allowed)
				(pads allowed)
				(copperpour not_allowed)
				(footprints allowed)
			)
			(placement
				(enabled no)
				(sheetname "")
			)
			(fill
				(thermal_gap 0.5)
				(thermal_bridge_width 0.5)
				(island_removal_mode 0)
			)
			(polygon
				(pts
					(xy 183.261 -72.2122) (xy 183.769 -72.2122) (xy 183.769 -72.5932) (xy 183.261 -72.5932)
				)
			)
		)
	)
	(footprint ""
		(layer "B.Cu")
		(at 100.6983 -135.4074 90)
		(property "Reference" "C8M2"
			(at 0 0 90)
			(layer "B.SilkS")
			(hide yes)
			(effects
				(font
					(size 1.27 1.27)
				)
				(justify mirror)
			)
		)
		(property "Value" ""
			(at 0 0 90)
			(layer "B.Fab")
			(effects
				(font
					(size 1.27 1.27)
				)
				(justify mirror)
			)
		)
		(duplicate_pad_numbers_are_jumpers no)
		(fp_rect
			(start 0.500126 1.598422)
			(end -0.500126 -0.201422)
			(stroke
				(width 0)
				(type default)
			)
			(fill no)
			(layer "B.CrtYd")
		)
		(fp_line
			(start 0.500126 -0.201422)
			(end -0.500126 -0.201422)
			(stroke
				(width 0.1)
				(type default)
			)
			(layer "B.Fab")
		)
		(fp_line
			(start -0.500126 -0.201422)
			(end -0.500126 1.598422)
			(stroke
				(width 0.1)
				(type default)
			)
			(layer "B.Fab")
		)
		(fp_line
			(start 0.500126 1.598422)
			(end 0.500126 -0.201422)
			(stroke
				(width 0.1)
				(type default)
			)
			(layer "B.Fab")
		)
		(fp_line
			(start -0.500126 1.598422)
			(end 0.500126 1.598422)
			(stroke
				(width 0.1)
				(type default)
			)
			(layer "B.Fab")
		)
		(pad "1" smd rect
			(at 0 0)
			(size 0.889 0.9906)
			(layers "B.Cu" "B.Mask" "B.Paste")
			(net "PVDDQ_KLM")
		)
		(pad "2" smd rect
			(at 0 1.397)
			(size 0.889 0.9906)
			(layers "B.Cu" "B.Mask" "B.Paste")
			(net "GND")
		)
		(zone
			(layer "B.Cu")
			(hatch none 0.5)
			(connect_pads
				(clearance 0)
			)
			(min_thickness 0.25)
			(keepout
				(tracks allowed)
				(vias not_allowed)
				(pads allowed)
				(copperpour not_allowed)
				(footprints allowed)
			)
			(placement
				(enabled no)
				(sheetname "")
			)
			(fill
				(thermal_gap 0.5)
				(thermal_bridge_width 0.5)
				(island_removal_mode 0)
			)
			(polygon
				(pts
					(xy 101.6508 -135.9027) (xy 101.1428 -135.9027) (xy 101.1428 -134.9121) (xy 101.6508 -134.9121)
				)
			)
		)
		(zone
			(layer "B.Cu")
			(hatch none 0.5)
			(connect_pads
				(clearance 0)
			)
			(min_thickness 0.25)
			(keepout
				(tracks not_allowed)
				(vias allowed)
				(pads allowed)
				(copperpour not_allowed)
				(footprints allowed)
			)
			(placement
				(enabled no)
				(sheetname "")
			)
			(fill
				(thermal_gap 0.5)
				(thermal_bridge_width 0.5)
				(island_removal_mode 0)
			)
			(polygon
				(pts
					(xy 101.6508 -135.9027) (xy 101.1428 -135.9027) (xy 101.1428 -134.9121) (xy 101.6508 -134.9121)
				)
			)
		)
	)
	(footprint ""
		(layer "B.Cu")
		(at 367.820956 -122.560842 -90)
		(property "Reference" "R784"
			(at 0.8382 -0.67818 270)
			(unlocked yes)
			(layer "B.SilkS")
			(effects
				(font
					(size 0.4064 0.254)
					(thickness 0.1524)
				)
				(justify left mirror)
			)
		)
		(property "Value" ""
			(at 0 0 90)
			(layer "B.Fab")
			(effects
				(font
					(size 1.27 1.27)
				)
				(justify mirror)
			)
		)
		(duplicate_pad_numbers_are_jumpers no)
		(fp_poly
			(pts
				(xy 0.2794 -0.1016) (xy -0.2794 -0.1016) (xy -0.2794 0.9906) (xy 0.2794 0.9906)
			)
			(stroke
				(width 0)
				(type default)
			)
			(fill no)
			(layer "B.CrtYd")
		)
		(fp_line
			(start -0.2794 0.9906)
			(end -0.2794 -0.1016)
			(stroke
				(width 0.1)
				(type default)
			)
			(layer "B.Fab")
		)
		(fp_line
			(start 0.2794 0.9906)
			(end -0.2794 0.9906)
			(stroke
				(width 0.1)
				(type default)
			)
			(layer "B.Fab")
		)
		(fp_line
			(start -0.2794 -0.1016)
			(end 0.2794 -0.1016)
			(stroke
				(width 0.1)
				(type default)
			)
			(layer "B.Fab")
		)
		(fp_line
			(start 0.2794 -0.1016)
			(end 0.2794 0.9906)
			(stroke
				(width 0.1)
				(type default)
			)
			(layer "B.Fab")
		)
		(pad "1" smd rect
			(at 0 0 90)
			(size 0.508 0.508)
			(layers "B.Cu" "B.Mask" "B.Paste")
			(net "P3E_CPU0_PE1_PCH_RXN<8>")
		)
		(pad "2" smd rect
			(at 0 0.889 90)
			(size 0.508 0.508)
			(layers "B.Cu" "B.Mask" "B.Paste")
			(net "P3E_CPU0_PE1_PCH_CON_RXN<8>")
		)
		(zone
			(layer "B.Cu")
			(hatch none 0.5)
			(connect_pads
				(clearance 0)
			)
			(min_thickness 0.25)
			(keepout
				(tracks not_allowed)
				(vias allowed)
				(pads allowed)
				(copperpour not_allowed)
				(footprints allowed)
			)
			(placement
				(enabled no)
				(sheetname "")
			)
			(fill
				(thermal_gap 0.5)
				(thermal_bridge_width 0.5)
				(island_removal_mode 0)
			)
			(polygon
				(pts
					(xy 367.185956 -122.306842) (xy 367.185956 -122.814842) (xy 367.566956 -122.814842) (xy 367.566956 -122.306842)
				)
			)
		)
		(zone
			(layer "B.Cu")
			(hatch none 0.5)
			(connect_pads
				(clearance 0)
			)
			(min_thickness 0.25)
			(keepout
				(tracks allowed)
				(vias not_allowed)
				(pads allowed)
				(copperpour not_allowed)
				(footprints allowed)
			)
			(placement
				(enabled no)
				(sheetname "")
			)
			(fill
				(thermal_gap 0.5)
				(thermal_bridge_width 0.5)
				(island_removal_mode 0)
			)
			(polygon
				(pts
					(xy 367.566956 -122.306842) (xy 367.566956 -122.814842) (xy 367.185956 -122.814842) (xy 367.185956 -122.306842)
				)
			)
		)
	)
)
